# BASEBOARD_FAB2 (Tioga Pass) — schematic netlist excerpt (pin names and nets, part order shuffled) for the footprints in the layout excerpt that follows; sources: Cadence DE-HDL packaged netlist, KiCad conversion of Wiwynn_Tioga_Pass_MB.brd

R768  RES  0.0 5% CHIP  pkg 0402  page 244 : A = P3E_CPU0_PE1_PCH_RXN<14> ; B = P3E_CPU0_PE1_PCH_CON_RXN<14>
CF14  SC22P50V2JN-4GP  5%  pkg SMD-BCG  page 213 : \1\ = VR_PVCCIO_CPU1_AIREF1 ; \2\ = ISENSE_PVCCIO_CPU1_PH1_IMON
R2L15  RES  2.0K 1% CHIP  pkg 0402  page 178 : A = P3V3_STBY ; B = SGPIO_PCH_SATA_DOUT0_R

(kicad_pcb
	(version 20260206)
	(generator "pcbnew")
	(generator_version "10.0")
	(general
		(thickness 1.6)
		(legacy_teardrops no)
	)
	(paper "A4")
	(title_block
		(title "Wiwynn_Tioga_Pass_MB.brd")
		(comment 1 "Tioga Pass / footprints 4094-4096 of 4770")
	)
	(layers
		(0 "F.Cu" signal "TOP")
		(4 "In1.Cu" signal "L2GND")
		(6 "In2.Cu" signal "L3")
		(8 "In3.Cu" signal "L4GND")
		(10 "In4.Cu" signal "L5")
		(12 "In5.Cu" signal "L6GND")
		(14 "In6.Cu" signal "L7VCC")
		(16 "In7.Cu" signal "L8VCC")
		(18 "In8.Cu" signal "L9GND")
		(20 "In9.Cu" signal "L10")
		(22 "In10.Cu" signal "L11GND")
		(24 "In11.Cu" signal "L12")
		(26 "In12.Cu" signal "L13GND")
		(2 "B.Cu" signal "BOTTOM")
		(9 "F.Adhes" user "F.Adhesive")
		(11 "B.Adhes" user "B.Adhesive")
		(13 "F.Paste" user "Package Geometry/Pastemask Top")
		(15 "B.Paste" user "Package Geometry/Pastemask Bottom")
		(5 "F.SilkS" user "Ref Des/Silkscreen Top")
		(7 "B.SilkS" user "Ref Des/Silkscreen Bottom")
		(1 "F.Mask" user "Board Geometry/Soldermask Top")
		(3 "B.Mask" user "Board Geometry/Soldermask Bottom")
		(17 "Dwgs.User" user "User.Drawings")
		(19 "Cmts.User" user "User.Comments")
		(21 "Eco1.User" user "User.Eco1")
		(23 "Eco2.User" user "User.Eco2")
		(25 "Edge.Cuts" user "Board Geometry/Outline")
		(27 "Margin" user)
		(31 "F.CrtYd" user "Package Geometry/Place Bound Top")
		(29 "B.CrtYd" user "Package Geometry/Place Bound Bottom")
		(35 "F.Fab" user "Ref Des/Assembly Top")
		(33 "B.Fab" user "Ref Des/Assembly Bottom")
	)
	(footprint ""
		(layer "B.Cu")
		(at 433.578 -151.257 -90)
		(property "Reference" "R2L15"
			(at 0 0 90)
			(layer "B.SilkS")
			(hide yes)
			(effects
				(font
					(size 1.27 1.27)
				)
				(justify mirror)
			)
		)
		(property "Value" ""
			(at 0 0 90)
			(layer "B.Fab")
			(effects
				(font
					(size 1.27 1.27)
				)
				(justify mirror)
			)
		)
		(duplicate_pad_numbers_are_jumpers no)
		(fp_poly
			(pts
				(xy 0.2794 -0.1016) (xy -0.2794 -0.1016) (xy -0.2794 0.9906) (xy 0.2794 0.9906)
			)
			(stroke
				(width 0)
				(type default)
			)
			(fill no)
			(layer "B.CrtYd")
		)
		(fp_line
			(start -0.2794 0.9906)
			(end -0.2794 -0.1016)
			(stroke
				(width 0.1)
				(type default)
			)
			(layer "B.Fab")
		)
		(fp_line
			(start 0.2794 0.9906)
			(end -0.2794 0.9906)
			(stroke
				(width 0.1)
				(type default)
			)
			(layer "B.Fab")
		)
		(fp_line
			(start -0.2794 -0.1016)
			(end 0.2794 -0.1016)
			(stroke
				(width 0.1)
				(type default)
			)
			(layer "B.Fab")
		)
		(fp_line
			(start 0.2794 -0.1016)
			(end 0.2794 0.9906)
			(stroke
				(width 0.1)
				(type default)
			)
			(layer "B.Fab")
		)
		(pad "1" smd rect
			(at 0 0 90)
			(size 0.508 0.508)
			(layers "B.Cu" "B.Mask" "B.Paste")
			(net "P3V3_STBY")
		)
		(pad "2" smd rect
			(at 0 0.889 90)
			(size 0.508 0.508)
			(layers "B.Cu" "B.Mask" "B.Paste")
			(net "SGPIO_PCH_SATA_DOUT0_R")
		)
		(zone
			(layer "B.Cu")
			(hatch none 0.5)
			(connect_pads
				(clearance 0)
			)
			(min_thickness 0.25)
			(keepout
				(tracks not_allowed)
				(vias allowed)
				(pads allowed)
				(copperpour not_allowed)
				(footprints allowed)
			)
			(placement
				(enabled no)
				(sheetname "")
			)
			(fill
				(thermal_gap 0.5)
				(thermal_bridge_width 0.5)
				(island_removal_mode 0)
			)
			(polygon
				(pts
					(xy 432.943 -151.003) (xy 432.943 -151.511) (xy 433.324 -151.511) (xy 433.324 -151.003)
				)
			)
		)
		(zone
			(layer "B.Cu")
			(hatch none 0.5)
			(connect_pads
				(clearance 0)
			)
			(min_thickness 0.25)
			(keepout
				(tracks allowed)
				(vias not_allowed)
				(pads allowed)
				(copperpour not_allowed)
				(footprints allowed)
			)
			(placement
				(enabled no)
				(sheetname "")
			)
			(fill
				(thermal_gap 0.5)
				(thermal_bridge_width 0.5)
				(island_removal_mode 0)
			)
			(polygon
				(pts
					(xy 433.324 -151.003) (xy 433.324 -151.511) (xy 432.943 -151.511) (xy 432.943 -151.003)
				)
			)
		)
	)
	(footprint ""
		(layer "B.Cu")
		(at 169.545 -65.024)
		(property "Reference" "CF14"
			(at 0 0 0)
			(layer "B.SilkS")
			(hide yes)
			(effects
				(font
					(size 1.27 1.27)
				)
				(justify mirror)
			)
		)
		(property "Value" "*"
			(at -1.1811 -2.8194 0)
			(unlocked yes)
			(layer "B.Fab")
			(hide yes)
			(effects
				(font
					(size 1.27 1.016)
					(thickness 0.1524)
				)
				(justify mirror)
			)
		)
		(property "Device Type" "SC22P50V2JN-4GP_SMD-BCG-SC22P5A"
			(at -1.1811 -4.3434 0)
			(unlocked yes)
			(layer "B.Fab")
			(hide yes)
			(effects
				(font
					(size 1.27 1.016)
					(thickness 0.1524)
				)
				(justify mirror)
			)
		)
		(duplicate_pad_numbers_are_jumpers no)
		(fp_rect
			(start 0.4318 0.9525)
			(end -0.4318 -0.9525)
			(stroke
				(width 0)
				(type default)
			)
			(fill no)
			(layer "B.CrtYd")
		)
		(fp_rect
			(start 0.4318 0.9525)
			(end -0.4318 -0.9525)
			(stroke
				(width 0)
				(type default)
			)
			(fill no)
			(layer "B.Fab")
		)
		(pad "1" smd custom
			(at 0 -0.4445 180)
			(size 0.1524 0.1524)
			(layers "B.Cu" "B.Mask" "B.Paste")
			(net "VR_PVCCIO_CPU1_AIREF1")
			(options
				(clearance outline)
				(anchor circle)
			)
			(primitives
				(gr_poly
					(pts
						(arc
							(start 0.3048 0.2032)
							(mid 0.275042 0.275042)
							(end 0.2032 0.3048)
						)
						(arc
							(start -0.2032 0.3048)
							(mid -0.275042 0.275042)
							(end -0.3048 0.2032)
						)
						(arc
							(start -0.3048 -0.2032)
							(mid -0.275042 -0.275042)
							(end -0.2032 -0.3048)
						)
						(arc
							(start 0.2032 -0.3048)
							(mid 0.275042 -0.275042)
							(end 0.3048 -0.2032)
						)
					)
					(width 0)
					(fill yes)
				)
			)
		)
		(pad "2" smd custom
			(at 0 0.4445 180)
			(size 0.1524 0.1524)
			(layers "B.Cu" "B.Mask" "B.Paste")
			(net "ISENSE_PVCCIO_CPU1_PH1_IMON")
			(options
				(clearance outline)
				(anchor circle)
			)
			(primitives
				(gr_poly
					(pts
						(arc
							(start 0.3048 0.2032)
							(mid 0.275042 0.275042)
							(end 0.2032 0.3048)
						)
						(arc
							(start -0.2032 0.3048)
							(mid -0.275042 0.275042)
							(end -0.3048 0.2032)
						)
						(arc
							(start -0.3048 -0.2032)
							(mid -0.275042 -0.275042)
							(end -0.2032 -0.3048)
						)
						(arc
							(start 0.2032 -0.3048)
							(mid 0.275042 -0.275042)
							(end 0.3048 -0.2032)
						)
					)
					(width 0)
					(fill yes)
				)
			)
		)
	)
	(footprint ""
		(layer "B.Cu")
		(at 349.133414 -125.227842 -90)
		(property "Reference" "R768"
			(at 0.8382 -0.67818 270)
			(unlocked yes)
			(layer "B.SilkS")
			(effects
				(font
					(size 0.4064 0.254)
					(thickness 0.1524)
				)
				(justify left mirror)
			)
		)
		(property "Value" ""
			(at 0 0 90)
			(layer "B.Fab")
			(effects
				(font
					(size 1.27 1.27)
				)
				(justify mirror)
			)
		)
		(duplicate_pad_numbers_are_jumpers no)
		(fp_poly
			(pts
				(xy 0.2794 -0.1016) (xy -0.2794 -0.1016) (xy -0.2794 0.9906) (xy 0.2794 0.9906)
			)
			(stroke
				(width 0)
				(type default)
			)
			(fill no)
			(layer "B.CrtYd")
		)
		(fp_line
			(start -0.2794 0.9906)
			(end -0.2794 -0.1016)
			(stroke
				(width 0.1)
				(type default)
			)
			(layer "B.Fab")
		)
		(fp_line
			(start 0.2794 0.9906)
			(end -0.2794 0.9906)
			(stroke
				(width 0.1)
				(type default)
			)
			(layer "B.Fab")
		)
		(fp_line
			(start -0.2794 -0.1016)
			(end 0.2794 -0.1016)
			(stroke
				(width 0.1)
				(type default)
			)
			(layer "B.Fab")
		)
		(fp_line
			(start 0.2794 -0.1016)
			(end 0.2794 0.9906)
			(stroke
				(width 0.1)
				(type default)
			)
			(layer "B.Fab")
		)
		(pad "1" smd rect
			(at 0 0 90)
			(size 0.508 0.508)
			(layers "B.Cu" "B.Mask" "B.Paste")
			(net "P3E_CPU0_PE1_PCH_RXN<14>")
		)
		(pad "2" smd rect
			(at 0 0.889 90)
			(size 0.508 0.508)
			(layers "B.Cu" "B.Mask" "B.Paste")
			(net "P3E_CPU0_PE1_PCH_CON_RXN<14>")
		)
		(zone
			(layer "B.Cu")
			(hatch none 0.5)
			(connect_pads
				(clearance 0)
			)
			(min_thickness 0.25)
			(keepout
				(tracks not_allowed)
				(vias allowed)
				(pads allowed)
				(copperpour not_allowed)
				(footprints allowed)
			)
			(placement
				(enabled no)
				(sheetname "")
			)
			(fill
				(thermal_gap 0.5)
				(thermal_bridge_width 0.5)
				(island_removal_mode 0)
			)
			(polygon
				(pts
					(xy 348.498414 -124.973842) (xy 348.498414 -125.481842) (xy 348.879414 -125.481842) (xy 348.879414 -124.973842)
				)
			)
		)
		(zone
			(layer "B.Cu")
			(hatch none 0.5)
			(connect_pads
				(clearance 0)
			)
			(min_thickness 0.25)
			(keepout
				(tracks allowed)
				(vias not_allowed)
				(pads allowed)
				(copperpour not_allowed)
				(footprints allowed)
			)
			(placement
				(enabled no)
				(sheetname "")
			)
			(fill
				(thermal_gap 0.5)
				(thermal_bridge_width 0.5)
				(island_removal_mode 0)
			)
			(polygon
				(pts
					(xy 348.879414 -124.973842) (xy 348.879414 -125.481842) (xy 348.498414 -125.481842) (xy 348.498414 -124.973842)
				)
			)
		)
	)
)
